(kicad_pcb
	(version 20260206)
	(generator "pcbnew")
	(generator_version "10.0")
	(general
		(thickness 1.6)
		(legacy_teardrops no)
	)
	(paper "A4")
	(title_block
		(title "04192023_DAF0TMB3IC0_F0TG_MB_C_brd_V02_OCP.brd")
		(comment 1 "Grand Teton / footprints 2970-2976 of 8354")
	)
	(layers
		(0 "F.Cu" signal "TOP")
		(4 "In1.Cu" signal "GND")
		(6 "In2.Cu" signal "IN1")
		(8 "In3.Cu" signal "GND1")
		(10 "In4.Cu" signal "IN2")
		(12 "In5.Cu" signal "GND2")
		(14 "In6.Cu" signal "IN3")
		(16 "In7.Cu" signal "GND3")
		(18 "In8.Cu" signal "VCC")
		(20 "In9.Cu" signal "VCC1")
		(22 "In10.Cu" signal "GND4")
		(24 "In11.Cu" signal "IN4")
		(26 "In12.Cu" signal "GND5")
		(28 "In13.Cu" signal "IN5")
		(30 "In14.Cu" signal "GND6")
		(32 "In15.Cu" signal "IN6")
		(34 "In16.Cu" signal "GND7")
		(2 "B.Cu" signal "BOTTOM")
		(9 "F.Adhes" user "F.Adhesive")
		(11 "B.Adhes" user "B.Adhesive")
		(13 "F.Paste" user "Package Geometry/Pastemask Top")
		(15 "B.Paste" user "Package Geometry/Pastemask Bottom")
		(5 "F.SilkS" user "Ref Des/Silkscreen Top")
		(7 "B.SilkS" user "Ref Des/Silkscreen Bottom")
		(1 "F.Mask" user "Board Geometry/Soldermask Top")
		(3 "B.Mask" user "Board Geometry/Soldermask Bottom")
		(17 "Dwgs.User" user "User.Drawings")
		(19 "Cmts.User" user "User.Comments")
		(21 "Eco1.User" user "User.Eco1")
		(23 "Eco2.User" user "User.Eco2")
		(25 "Edge.Cuts" user "Board Geometry/Outline")
		(27 "Margin" user)
		(31 "F.CrtYd" user "Package Geometry/Place Bound Top")
		(29 "B.CrtYd" user "Package Geometry/Place Bound Bottom")
		(35 "F.Fab" user "Ref Des/Assembly Top")
		(33 "B.Fab" user "Ref Des/Assembly Bottom")
	)
	(footprint ""
		(layer "F.Cu")
		(at 27.559 -359.283)
		(property "Reference" "PC358"
			(at 0 0 0)
			(layer "F.SilkS")
			(hide yes)
			(effects
				(font
					(size 1.27 1.27)
				)
			)
		)
		(property "Value" ""
			(at 0 0 0)
			(layer "F.Fab")
			(effects
				(font
					(size 1.27 1.27)
				)
			)
		)
		(duplicate_pad_numbers_are_jumpers no)
		(fp_line
			(start -0.7874 -0.4064)
			(end 0.7874 -0.4064)
			(stroke
				(width 0.1524)
				(type default)
			)
			(layer "F.SilkS")
		)
		(fp_line
			(start -0.7874 0.4064)
			(end -0.7874 -0.4064)
			(stroke
				(width 0.1524)
				(type default)
			)
			(layer "F.SilkS")
		)
		(fp_line
			(start 0.7874 -0.4064)
			(end 0.7874 0.4064)
			(stroke
				(width 0.1524)
				(type default)
			)
			(layer "F.SilkS")
		)
		(fp_line
			(start 0.7874 0.4064)
			(end -0.7874 0.4064)
			(stroke
				(width 0.1524)
				(type default)
			)
			(layer "F.SilkS")
		)
		(fp_line
			(start -0.67945 -0.305054)
			(end -0.12065 -0.305054)
			(stroke
				(width 0.1)
				(type default)
			)
			(layer "F.Fab")
		)
		(fp_line
			(start -0.67945 0.3048)
			(end -0.67945 -0.305054)
			(stroke
				(width 0.1)
				(type default)
			)
			(layer "F.Fab")
		)
		(fp_line
			(start -0.12065 -0.305054)
			(end -0.12065 -0.2794)
			(stroke
				(width 0.1)
				(type default)
			)
			(layer "F.Fab")
		)
		(fp_line
			(start -0.12065 -0.2794)
			(end 0.12065 -0.2794)
			(stroke
				(width 0.1)
				(type default)
			)
			(layer "F.Fab")
		)
		(fp_line
			(start -0.12065 0.2794)
			(end -0.12065 0.3048)
			(stroke
				(width 0.1)
				(type default)
			)
			(layer "F.Fab")
		)
		(fp_line
			(start -0.12065 0.3048)
			(end -0.67945 0.3048)
			(stroke
				(width 0.1)
				(type default)
			)
			(layer "F.Fab")
		)
		(fp_line
			(start 0.120396 0.2794)
			(end -0.12065 0.2794)
			(stroke
				(width 0.1)
				(type default)
			)
			(layer "F.Fab")
		)
		(fp_line
			(start 0.120396 0.3048)
			(end 0.120396 0.2794)
			(stroke
				(width 0.1)
				(type default)
			)
			(layer "F.Fab")
		)
		(fp_line
			(start 0.12065 -0.3048)
			(end 0.67945 -0.3048)
			(stroke
				(width 0.1)
				(type default)
			)
			(layer "F.Fab")
		)
		(fp_line
			(start 0.12065 -0.2794)
			(end 0.12065 -0.3048)
			(stroke
				(width 0.1)
				(type default)
			)
			(layer "F.Fab")
		)
		(fp_line
			(start 0.67945 -0.3048)
			(end 0.67945 0.3048)
			(stroke
				(width 0.1)
				(type default)
			)
			(layer "F.Fab")
		)
		(fp_line
			(start 0.67945 0.3048)
			(end 0.120396 0.3048)
			(stroke
				(width 0.1)
				(type default)
			)
			(layer "F.Fab")
		)
		(pad "1" smd circle
			(at -0.40005 0)
			(size 0 0)
			(layers "F.Cu" "F.Mask" "F.Paste")
			(net "VSENSE_PVDDCR_CPU1_P1_VSEN0")
		)
		(pad "2" smd circle
			(at 0.40005 0)
			(size 0 0)
			(layers "F.Cu" "F.Mask" "F.Paste")
			(net "VSENSE_VSS_SENSE_C_P1")
		)
	)
	(footprint ""
		(layer "F.Cu")
		(at 407.685748 -16.100298 90)
		(property "Reference" "C1793"
			(at 0 0 90)
			(layer "F.SilkS")
			(hide yes)
			(effects
				(font
					(size 1.27 1.27)
				)
			)
		)
		(property "Value" ""
			(at 0 0 90)
			(layer "F.Fab")
			(effects
				(font
					(size 1.27 1.27)
				)
			)
		)
		(duplicate_pad_numbers_are_jumpers no)
		(fp_line
			(start 0.299974 -0.150114)
			(end 0.299974 0.150114)
			(stroke
				(width 0.1)
				(type default)
			)
			(layer "F.Fab")
		)
		(fp_line
			(start -0.299974 -0.150114)
			(end 0.299974 -0.150114)
			(stroke
				(width 0.1)
				(type default)
			)
			(layer "F.Fab")
		)
		(fp_line
			(start 0.299974 0.150114)
			(end -0.299974 0.150114)
			(stroke
				(width 0.1)
				(type default)
			)
			(layer "F.Fab")
		)
		(fp_line
			(start -0.299974 0.150114)
			(end -0.299974 -0.150114)
			(stroke
				(width 0.1)
				(type default)
			)
			(layer "F.Fab")
		)
		(pad "1" smd rect
			(at -0.2667 0 90)
			(size 0.3048 0.381)
			(layers "F.Cu" "F.Mask" "F.Paste")
			(net "P5E_CPU0_G3_TX_C_DP<9>")
		)
		(pad "2" smd rect
			(at 0.2667 0 90)
			(size 0.3048 0.381)
			(layers "F.Cu" "F.Mask" "F.Paste")
			(net "P5E_CPU0_G3_TX_DP<9>")
		)
	)
	(footprint ""
		(layer "F.Cu")
		(at 271.085056 -122.84837 180)
		(property "Reference" "R3711"
			(at 0 0 180)
			(layer "F.SilkS")
			(hide yes)
			(effects
				(font
					(size 1.27 1.27)
				)
			)
		)
		(property "Value" ""
			(at 0 0 180)
			(layer "F.Fab")
			(effects
				(font
					(size 1.27 1.27)
				)
			)
		)
		(duplicate_pad_numbers_are_jumpers no)
		(fp_line
			(start 0.7874 0.4064)
			(end -0.7874 0.4064)
			(stroke
				(width 0.1524)
				(type default)
			)
			(layer "F.SilkS")
		)
		(fp_line
			(start 0.7874 -0.4064)
			(end 0.7874 0.4064)
			(stroke
				(width 0.1524)
				(type default)
			)
			(layer "F.SilkS")
		)
		(fp_line
			(start -0.7874 0.4064)
			(end -0.7874 -0.4064)
			(stroke
				(width 0.1524)
				(type default)
			)
			(layer "F.SilkS")
		)
		(fp_line
			(start -0.7874 -0.4064)
			(end 0.7874 -0.4064)
			(stroke
				(width 0.1524)
				(type default)
			)
			(layer "F.SilkS")
		)
		(fp_line
			(start 0.67945 0.3048)
			(end 0.120396 0.3048)
			(stroke
				(width 0.1)
				(type default)
			)
			(layer "F.Fab")
		)
		(fp_line
			(start 0.67945 -0.3048)
			(end 0.67945 0.3048)
			(stroke
				(width 0.1)
				(type default)
			)
			(layer "F.Fab")
		)
		(fp_line
			(start 0.12065 -0.2794)
			(end 0.12065 -0.3048)
			(stroke
				(width 0.1)
				(type default)
			)
			(layer "F.Fab")
		)
		(fp_line
			(start 0.12065 -0.3048)
			(end 0.67945 -0.3048)
			(stroke
				(width 0.1)
				(type default)
			)
			(layer "F.Fab")
		)
		(fp_line
			(start 0.120396 0.3048)
			(end 0.120396 0.2794)
			(stroke
				(width 0.1)
				(type default)
			)
			(layer "F.Fab")
		)
		(fp_line
			(start 0.120396 0.2794)
			(end -0.12065 0.2794)
			(stroke
				(width 0.1)
				(type default)
			)
			(layer "F.Fab")
		)
		(fp_line
			(start -0.12065 0.3048)
			(end -0.67945 0.3048)
			(stroke
				(width 0.1)
				(type default)
			)
			(layer "F.Fab")
		)
		(fp_line
			(start -0.12065 0.2794)
			(end -0.12065 0.3048)
			(stroke
				(width 0.1)
				(type default)
			)
			(layer "F.Fab")
		)
		(fp_line
			(start -0.12065 -0.2794)
			(end 0.12065 -0.2794)
			(stroke
				(width 0.1)
				(type default)
			)
			(layer "F.Fab")
		)
		(fp_line
			(start -0.12065 -0.305054)
			(end -0.12065 -0.2794)
			(stroke
				(width 0.1)
				(type default)
			)
			(layer "F.Fab")
		)
		(fp_line
			(start -0.67945 0.3048)
			(end -0.67945 -0.305054)
			(stroke
				(width 0.1)
				(type default)
			)
			(layer "F.Fab")
		)
		(fp_line
			(start -0.67945 -0.305054)
			(end -0.12065 -0.305054)
			(stroke
				(width 0.1)
				(type default)
			)
			(layer "F.Fab")
		)
		(pad "1" smd circle
			(at -0.40005 0 180)
			(size 0 0)
			(layers "F.Cu" "F.Mask" "F.Paste")
			(net "SMB_VR_SENSOR_3V3AUX_SCL")
		)
		(pad "2" smd circle
			(at 0.40005 0 180)
			(size 0 0)
			(layers "F.Cu" "F.Mask" "F.Paste")
			(net "SMB_VR_SENSOR_3V3AUX_SCL_R")
		)
	)
	(footprint ""
		(layer "F.Cu")
		(at 78.401164 -408.517344 -90)
		(property "Reference" "C6650"
			(at 0 0 270)
			(layer "F.SilkS")
			(hide yes)
			(effects
				(font
					(size 1.27 1.27)
				)
			)
		)
		(property "Value" ""
			(at 0 0 270)
			(layer "F.Fab")
			(effects
				(font
					(size 1.27 1.27)
				)
			)
		)
		(duplicate_pad_numbers_are_jumpers no)
		(fp_line
			(start -0.299974 0.150114)
			(end -0.299974 -0.150114)
			(stroke
				(width 0.1)
				(type default)
			)
			(layer "F.Fab")
		)
		(fp_line
			(start 0.299974 0.150114)
			(end -0.299974 0.150114)
			(stroke
				(width 0.1)
				(type default)
			)
			(layer "F.Fab")
		)
		(fp_line
			(start -0.299974 -0.150114)
			(end 0.299974 -0.150114)
			(stroke
				(width 0.1)
				(type default)
			)
			(layer "F.Fab")
		)
		(fp_line
			(start 0.299974 -0.150114)
			(end 0.299974 0.150114)
			(stroke
				(width 0.1)
				(type default)
			)
			(layer "F.Fab")
		)
		(pad "1" smd rect
			(at -0.2667 0 270)
			(size 0.3048 0.381)
			(layers "F.Cu" "F.Mask" "F.Paste")
			(net "P5E_CPU1_P0_TX_BUF_C_DN<10>")
		)
		(pad "2" smd rect
			(at 0.2667 0 270)
			(size 0.3048 0.381)
			(layers "F.Cu" "F.Mask" "F.Paste")
			(net "P5E_CPU1_P0_TX_BUF_DN<10>")
		)
	)
	(footprint ""
		(layer "F.Cu")
		(at 368.324384 -14.394942)
		(property "Reference" "U104"
			(at -1.8034 -2.301748 0)
			(unlocked yes)
			(layer "F.SilkS")
			(effects
				(font
					(size 0.7874 0.5842)
					(thickness 0.1524)
				)
				(justify left)
			)
		)
		(property "Value" ""
			(at 0 0 0)
			(layer "F.Fab")
			(effects
				(font
					(size 1.27 1.27)
				)
			)
		)
		(duplicate_pad_numbers_are_jumpers no)
		(fp_line
			(start -1.733296 -1.549908)
			(end -1.733296 1.549908)
			(stroke
				(width 0.1524)
				(type default)
			)
			(layer "F.SilkS")
		)
		(fp_line
			(start -1.733296 1.549908)
			(end 1.733296 1.549908)
			(stroke
				(width 0.1524)
				(type default)
			)
			(layer "F.SilkS")
		)
		(fp_line
			(start -0.660908 -1.549908)
			(end -1.733296 -1.549908)
			(stroke
				(width 0.1524)
				(type default)
			)
			(layer "F.SilkS")
		)
		(fp_line
			(start 0 -0.889)
			(end -0.660908 -1.549908)
			(stroke
				(width 0.1524)
				(type default)
			)
			(layer "F.SilkS")
		)
		(fp_line
			(start 0.660908 -1.549908)
			(end 0 -0.889)
			(stroke
				(width 0.1524)
				(type default)
			)
			(layer "F.SilkS")
		)
		(fp_line
			(start 1.733296 -1.549908)
			(end 0.660908 -1.549908)
			(stroke
				(width 0.1524)
				(type default)
			)
			(layer "F.SilkS")
		)
		(fp_line
			(start 1.733296 1.549908)
			(end 1.733296 -1.549908)
			(stroke
				(width 0.1524)
				(type default)
			)
			(layer "F.SilkS")
		)
		(fp_poly
			(pts
				(xy -1.927606 -0.774954) (xy -2.419096 -0.49022) (xy -2.450338 -0.997204)
			)
			(stroke
				(width 0)
				(type default)
			)
			(fill yes)
			(layer "F.SilkS")
		)
		(fp_line
			(start -0.849884 -1.549908)
			(end -0.849884 1.549908)
			(stroke
				(width 0.1)
				(type default)
			)
			(layer "F.Fab")
		)
		(fp_line
			(start -0.849884 1.549908)
			(end 0.849884 1.549908)
			(stroke
				(width 0.1)
				(type default)
			)
			(layer "F.Fab")
		)
		(fp_line
			(start 0.849884 -1.549908)
			(end -0.849884 -1.549908)
			(stroke
				(width 0.1)
				(type default)
			)
			(layer "F.Fab")
		)
		(fp_line
			(start 0.849884 1.549908)
			(end 0.849884 -1.549908)
			(stroke
				(width 0.1)
				(type default)
			)
			(layer "F.Fab")
		)
		(fp_poly
			(pts
				(xy -2.4384 -1.20396) (xy -2.4384 -0.69596) (xy -1.9304 -0.94996)
			)
			(stroke
				(width 0)
				(type default)
			)
			(fill yes)
			(layer "F.Fab")
		)
		(pad "1" smd rect
			(at -1.199896 -0.94996 270)
			(size 0.5588 0.8128)
			(layers "F.Cu" "F.Mask" "F.Paste")
			(net "NC_U104_NC1")
		)
		(pad "2" smd rect
			(at -1.199896 0 270)
			(size 0.5588 0.8128)
			(layers "F.Cu" "F.Mask" "F.Paste")
			(net "FM_SYS_THROTTLE_N")
		)
		(pad "3" smd rect
			(at -1.199896 0.94996 270)
			(size 0.5588 0.8128)
			(layers "F.Cu" "F.Mask" "F.Paste")
			(net "GND")
		)
		(pad "4" smd rect
			(at 1.199896 0.94996 270)
			(size 0.5588 0.8128)
			(layers "F.Cu" "F.Mask" "F.Paste")
			(net "OCP_SFF_PWRBRK_BUFF_N")
		)
		(pad "5" smd rect
			(at 1.199896 -0.94996 270)
			(size 0.5588 0.8128)
			(layers "F.Cu" "F.Mask" "F.Paste")
			(net "P3V3_AUX")
		)
	)
	(footprint ""
		(layer "F.Cu")
		(at 157.15107 -74.75347 90)
		(property "Reference" "R6063"
			(at 0 0 90)
			(layer "F.SilkS")
			(hide yes)
			(effects
				(font
					(size 1.27 1.27)
				)
			)
		)
		(property "Value" ""
			(at 0 0 90)
			(layer "F.Fab")
			(effects
				(font
					(size 1.27 1.27)
				)
			)
		)
		(duplicate_pad_numbers_are_jumpers no)
		(fp_line
			(start 0.7874 -0.4064)
			(end 0.7874 0.4064)
			(stroke
				(width 0.1524)
				(type default)
			)
			(layer "F.SilkS")
		)
		(fp_line
			(start -0.7874 -0.4064)
			(end 0.7874 -0.4064)
			(stroke
				(width 0.1524)
				(type default)
			)
			(layer "F.SilkS")
		)
		(fp_line
			(start 0.7874 0.4064)
			(end -0.7874 0.4064)
			(stroke
				(width 0.1524)
				(type default)
			)
			(layer "F.SilkS")
		)
		(fp_line
			(start -0.7874 0.4064)
			(end -0.7874 -0.4064)
			(stroke
				(width 0.1524)
				(type default)
			)
			(layer "F.SilkS")
		)
		(fp_line
			(start -0.12065 -0.305054)
			(end -0.12065 -0.2794)
			(stroke
				(width 0.1)
				(type default)
			)
			(layer "F.Fab")
		)
		(fp_line
			(start -0.67945 -0.305054)
			(end -0.12065 -0.305054)
			(stroke
				(width 0.1)
				(type default)
			)
			(layer "F.Fab")
		)
		(fp_line
			(start 0.67945 -0.3048)
			(end 0.67945 0.3048)
			(stroke
				(width 0.1)
				(type default)
			)
			(layer "F.Fab")
		)
		(fp_line
			(start 0.12065 -0.3048)
			(end 0.67945 -0.3048)
			(stroke
				(width 0.1)
				(type default)
			)
			(layer "F.Fab")
		)
		(fp_line
			(start 0.12065 -0.2794)
			(end 0.12065 -0.3048)
			(stroke
				(width 0.1)
				(type default)
			)
			(layer "F.Fab")
		)
		(fp_line
			(start -0.12065 -0.2794)
			(end 0.12065 -0.2794)
			(stroke
				(width 0.1)
				(type default)
			)
			(layer "F.Fab")
		)
		(fp_line
			(start 0.120396 0.2794)
			(end -0.12065 0.2794)
			(stroke
				(width 0.1)
				(type default)
			)
			(layer "F.Fab")
		)
		(fp_line
			(start -0.12065 0.2794)
			(end -0.12065 0.3048)
			(stroke
				(width 0.1)
				(type default)
			)
			(layer "F.Fab")
		)
		(fp_line
			(start 0.67945 0.3048)
			(end 0.120396 0.3048)
			(stroke
				(width 0.1)
				(type default)
			)
			(layer "F.Fab")
		)
		(fp_line
			(start 0.120396 0.3048)
			(end 0.120396 0.2794)
			(stroke
				(width 0.1)
				(type default)
			)
			(layer "F.Fab")
		)
		(fp_line
			(start -0.12065 0.3048)
			(end -0.67945 0.3048)
			(stroke
				(width 0.1)
				(type default)
			)
			(layer "F.Fab")
		)
		(fp_line
			(start -0.67945 0.3048)
			(end -0.67945 -0.305054)
			(stroke
				(width 0.1)
				(type default)
			)
			(layer "F.Fab")
		)
		(pad "1" smd circle
			(at -0.40005 0 90)
			(size 0 0)
			(layers "F.Cu" "F.Mask" "F.Paste")
			(net "IRQ_OCP_V3_2_WAKE_BUF_N")
		)
		(pad "2" smd circle
			(at 0.40005 0 90)
			(size 0 0)
			(layers "F.Cu" "F.Mask" "F.Paste")
			(net "IRQ_LVC3_WAKE_N")
		)
	)
	(footprint ""
		(layer "F.Cu")
		(at 127.643128 -166.926768 -90)
		(property "Reference" "PR526"
			(at 0 0 270)
			(layer "F.SilkS")
			(hide yes)
			(effects
				(font
					(size 1.27 1.27)
				)
			)
		)
		(property "Value" ""
			(at 0 0 270)
			(layer "F.Fab")
			(effects
				(font
					(size 1.27 1.27)
				)
			)
		)
		(duplicate_pad_numbers_are_jumpers no)
		(fp_line
			(start -0.7874 0.4064)
			(end -0.7874 -0.4064)
			(stroke
				(width 0.1524)
				(type default)
			)
			(layer "F.SilkS")
		)
		(fp_line
			(start 0.7874 0.4064)
			(end -0.7874 0.4064)
			(stroke
				(width 0.1524)
				(type default)
			)
			(layer "F.SilkS")
		)
		(fp_line
			(start -0.7874 -0.4064)
			(end 0.7874 -0.4064)
			(stroke
				(width 0.1524)
				(type default)
			)
			(layer "F.SilkS")
		)
		(fp_line
			(start 0.7874 -0.4064)
			(end 0.7874 0.4064)
			(stroke
				(width 0.1524)
				(type default)
			)
			(layer "F.SilkS")
		)
		(fp_line
			(start -0.67945 0.3048)
			(end -0.67945 -0.305054)
			(stroke
				(width 0.1)
				(type default)
			)
			(layer "F.Fab")
		)
		(fp_line
			(start -0.12065 0.3048)
			(end -0.67945 0.3048)
			(stroke
				(width 0.1)
				(type default)
			)
			(layer "F.Fab")
		)
		(fp_line
			(start 0.120396 0.3048)
			(end 0.120396 0.2794)
			(stroke
				(width 0.1)
				(type default)
			)
			(layer "F.Fab")
		)
		(fp_line
			(start 0.67945 0.3048)
			(end 0.120396 0.3048)
			(stroke
				(width 0.1)
				(type default)
			)
			(layer "F.Fab")
		)
		(fp_line
			(start -0.12065 0.2794)
			(end -0.12065 0.3048)
			(stroke
				(width 0.1)
				(type default)
			)
			(layer "F.Fab")
		)
		(fp_line
			(start 0.120396 0.2794)
			(end -0.12065 0.2794)
			(stroke
				(width 0.1)
				(type default)
			)
			(layer "F.Fab")
		)
		(fp_line
			(start -0.12065 -0.2794)
			(end 0.12065 -0.2794)
			(stroke
				(width 0.1)
				(type default)
			)
			(layer "F.Fab")
		)
		(fp_line
			(start 0.12065 -0.2794)
			(end 0.12065 -0.3048)
			(stroke
				(width 0.1)
				(type default)
			)
			(layer "F.Fab")
		)
		(fp_line
			(start 0.12065 -0.3048)
			(end 0.67945 -0.3048)
			(stroke
				(width 0.1)
				(type default)
			)
			(layer "F.Fab")
		)
		(fp_line
			(start 0.67945 -0.3048)
			(end 0.67945 0.3048)
			(stroke
				(width 0.1)
				(type default)
			)
			(layer "F.Fab")
		)
		(fp_line
			(start -0.67945 -0.305054)
			(end -0.12065 -0.305054)
			(stroke
				(width 0.1)
				(type default)
			)
			(layer "F.Fab")
		)
		(fp_line
			(start -0.12065 -0.305054)
			(end -0.12065 -0.2794)
			(stroke
				(width 0.1)
				(type default)
			)
			(layer "F.Fab")
		)
		(pad "1" smd circle
			(at -0.40005 0 270)
			(size 0 0)
			(layers "F.Cu" "F.Mask" "F.Paste")
			(net "SW_PVDDCR_SOC_P1_SW2_RC")
		)
		(pad "2" smd circle
			(at 0.40005 0 270)
			(size 0 0)
			(layers "F.Cu" "F.Mask" "F.Paste")
			(net "GND")
		)
	)
)
